#ISCELL
  mstr_misc dns *
  *
#ISCELL
  pure_quanta quanta_title_block_c *
  *
#ISCELL
  logical_power universal_gnd *
  page276_i1
#ISCELL
  standard offpage *
  page276_i10
#ISCELL
  logical_power universal_gnd *
  page276_i11
#CELL
  pure_quanta q_cap *
  page276_i12
#CELL
  pure_quanta q_cap *
  page276_i13
#ISCELL
  logical_power universal_gnd *
  page276_i14
#CELL
  pure_quanta isl99390frztr5935 *
  page276_i15
#ISCELL
  logical_power universal_gnd *
  page276_i16
#CELL
  pure_quanta q_res *
  page276_i17
#CELL
  pure_quanta q_res *
  page276_i18
#ISCELL
  logical_power vcc15 *
  page276_i19
#CELL
  pure_quanta q_res *
  page276_i2
#CELL
  pure_quanta q_cap *
  page276_i20
#ISCELL
  standard offpage *
  page276_i21
#ISCELL
  standard offpage *
  page276_i22
#CELL
  pure_quanta q_cap *
  page276_i23
#CELL
  pure_quanta isl99390frztr5935 *
  page276_i24
#ISCELL
  standard offpage *
  page276_i25
#ISCELL
  standard offpage *
  page276_i26
#CELL
  pure_quanta q_cap *
  page276_i27
#ISCELL
  logical_power universal_gnd *
  page276_i28
#CELL
  pure_quanta q_res *
  page276_i29
#ISCELL
  logical_power universal_gnd *
  page276_i3
#ISCELL
  logical_power universal_gnd *
  page276_i30
#CELL
  pure_quanta q_cap *
  page276_i31
#ISCELL
  logical_power vcc15 *
  page276_i32
#CELL
  pure_quanta q_cap *
  page276_i33
#ISCELL
  logical_power universal_gnd *
  page276_i34
#CELL
  pure_quanta q_cap *
  page276_i35
#CELL
  pure_quanta q_cap *
  page276_i36
#CELL
  pure_quanta q_cap *
  page276_i37
#CELL
  pure_quanta q_cap *
  page276_i38
#CELL
  pure_quanta q_cap *
  page276_i39
#ISCELL
  logical_power universal_gnd *
  page276_i4
#CELL
  pure_quanta q_res *
  page276_i40
#CELL
  pure_quanta q_cap *
  page276_i41
#CELL
  pure_quanta q_cap *
  page276_i42
#CELL
  pure_quanta q_res *
  page276_i43
#CELL
  pure_quanta q_inductor *
  page276_i44
#CELL
  pure_quanta q_cap *
  page276_i45
#ISCELL
  logical_power universal_gnd *
  page276_i46
#CELL
  pure_quanta q_cap *
  page276_i47
#CELL
  pure_quanta q_cap *
  page276_i48
#ISCELL
  logical_power universal_gnd *
  page276_i49
#CELL
  pure_quanta q_res *
  page276_i5
#CELL
  pure_quanta q_cap *
  page276_i50
#ISCELL
  logical_power vcc15 *
  page276_i51
#CELL
  pure_quanta q_cap *
  page276_i52
#ISCELL
  logical_power vcc15 *
  page276_i53
#CELL
  pure_quanta q_res *
  page276_i54
#CELL
  pure_quanta q_capp *
  page276_i55
#CELL
  pure_quanta q_cap *
  page276_i56
#CELL
  pure_quanta q_inductor *
  page276_i57
#CELL
  pure_quanta q_cap *
  page276_i58
#ISCELL
  logical_power universal_gnd *
  page276_i59
#ISCELL
  logical_power universal_gnd *
  page276_i6
#CELL
  pure_quanta q_cap *
  page276_i60
#ISCELL
  logical_power vcc15 *
  page276_i61
#CELL
  pure_quanta q_cap *
  page276_i62
#ISCELL
  logical_power gnd *
  page276_i63
#CELL
  pure_quanta q_inductor *
  page276_i64
#ISCELL
  logical_power vcc15 *
  page276_i65
#CELL
  pure_quanta q_cap *
  page276_i66
#CELL
  pure_quanta q_capp *
  page276_i67
#CELL
  pure_quanta q_cap *
  page276_i68
#ISCELL
  logical_power universal_gnd *
  page276_i69
#ISCELL
  standard offpage *
  page276_i7
#CELL
  pure_quanta q_capp *
  page276_i70
#ISCELL
  logical_power universal_gnd *
  page276_i71
#CELL
  pure_quanta q_capp *
  page276_i72
#CELL
  pure_quanta q_capp *
  page276_i73
#ISCELL
  logical_power vcc15 *
  page276_i74
#CELL
  pure_quanta q_cap *
  page276_i75
#ISCELL
  logical_power vcc15 *
  page276_i76
#CELL
  pure_quanta q_cap *
  page276_i77
#CELL
  pure_quanta q_cap *
  page276_i78
#ISCELL
  logical_power universal_gnd *
  page276_i79
#ISCELL
  standard offpage *
  page276_i8
#CELL
  pure_quanta q_cap *
  page276_i80
#CELL
  pure_quanta q_capp *
  page276_i81
#ISCELL
  logical_power vcc15 *
  page276_i82
#ISCELL
  standard offpage *
  page276_i9
